(kicad_pcb
	(version 20260206)
	(generator "pcbnew")
	(generator_version "10.0")
	(general
		(thickness 1.6)
		(legacy_teardrops no)
	)
	(paper "A4")
	(title_block
		(title "Wiwynn_Tioga_Pass_MB.brd")
		(comment 1 "Tioga Pass / footprints 3804-3810 of 4770")
	)
	(layers
		(0 "F.Cu" signal "TOP")
		(4 "In1.Cu" signal "L2GND")
		(6 "In2.Cu" signal "L3")
		(8 "In3.Cu" signal "L4GND")
		(10 "In4.Cu" signal "L5")
		(12 "In5.Cu" signal "L6GND")
		(14 "In6.Cu" signal "L7VCC")
		(16 "In7.Cu" signal "L8VCC")
		(18 "In8.Cu" signal "L9GND")
		(20 "In9.Cu" signal "L10")
		(22 "In10.Cu" signal "L11GND")
		(24 "In11.Cu" signal "L12")
		(26 "In12.Cu" signal "L13GND")
		(2 "B.Cu" signal "BOTTOM")
		(9 "F.Adhes" user "F.Adhesive")
		(11 "B.Adhes" user "B.Adhesive")
		(13 "F.Paste" user "Package Geometry/Pastemask Top")
		(15 "B.Paste" user "Package Geometry/Pastemask Bottom")
		(5 "F.SilkS" user "Ref Des/Silkscreen Top")
		(7 "B.SilkS" user "Ref Des/Silkscreen Bottom")
		(1 "F.Mask" user "Board Geometry/Soldermask Top")
		(3 "B.Mask" user "Board Geometry/Soldermask Bottom")
		(17 "Dwgs.User" user "User.Drawings")
		(19 "Cmts.User" user "User.Comments")
		(21 "Eco1.User" user "User.Eco1")
		(23 "Eco2.User" user "User.Eco2")
		(25 "Edge.Cuts" user "Board Geometry/Outline")
		(27 "Margin" user)
		(31 "F.CrtYd" user "Package Geometry/Place Bound Top")
		(29 "B.CrtYd" user "Package Geometry/Place Bound Bottom")
		(35 "F.Fab" user "Ref Des/Assembly Top")
		(33 "B.Fab" user "Ref Des/Assembly Bottom")
	)
	(footprint ""
		(layer "B.Cu")
		(at 441.7187 -64.9986 -90)
		(property "Reference" "C2P10"
			(at 0 0 90)
			(layer "B.SilkS")
			(hide yes)
			(effects
				(font
					(size 1.27 1.27)
				)
				(justify mirror)
			)
		)
		(property "Value" ""
			(at 0 0 90)
			(layer "B.Fab")
			(effects
				(font
					(size 1.27 1.27)
				)
				(justify mirror)
			)
		)
		(duplicate_pad_numbers_are_jumpers no)
		(fp_line
			(start -0.9017 1.953768)
			(end -0.9017 0.824484)
			(stroke
				(width 0.1524)
				(type default)
			)
			(layer "B.SilkS")
		)
		(fp_line
			(start 0.9017 1.953006)
			(end 0.9017 0.823976)
			(stroke
				(width 0.1524)
				(type default)
			)
			(layer "B.SilkS")
		)
		(fp_poly
			(pts
				(xy 0.9017 -0.3048) (xy -0.9017 -0.3048) (xy -0.9017 3.0988) (xy 0.9017 3.0988)
			)
			(stroke
				(width 0)
				(type default)
			)
			(fill no)
			(layer "B.CrtYd")
		)
		(fp_line
			(start -0.9017 3.0988)
			(end -0.9017 -0.3048)
			(stroke
				(width 0.1)
				(type default)
			)
			(layer "B.Fab")
		)
		(fp_line
			(start 0.9017 3.0988)
			(end -0.9017 3.0988)
			(stroke
				(width 0.1)
				(type default)
			)
			(layer "B.Fab")
		)
		(fp_line
			(start -0.9017 -0.3048)
			(end 0.9017 -0.3048)
			(stroke
				(width 0.1)
				(type default)
			)
			(layer "B.Fab")
		)
		(fp_line
			(start 0.9017 -0.3048)
			(end 0.9017 3.0988)
			(stroke
				(width 0.1)
				(type default)
			)
			(layer "B.Fab")
		)
		(pad "1" smd rect
			(at 0 0 90)
			(size 1.524 1.016)
			(layers "B.Cu" "B.Mask" "B.Paste")
			(net "P12V_STBY")
		)
		(pad "2" smd rect
			(at 0 2.794 90)
			(size 1.524 1.016)
			(layers "B.Cu" "B.Mask" "B.Paste")
			(net "GND")
		)
		(zone
			(layer "B.Cu")
			(hatch none 0.5)
			(connect_pads
				(clearance 0)
			)
			(min_thickness 0.25)
			(keepout
				(tracks allowed)
				(vias not_allowed)
				(pads allowed)
				(copperpour not_allowed)
				(footprints allowed)
			)
			(placement
				(enabled no)
				(sheetname "")
			)
			(fill
				(thermal_gap 0.5)
				(thermal_bridge_width 0.5)
				(island_removal_mode 0)
			)
			(polygon
				(pts
					(xy 441.2107 -65.7606) (xy 439.4327 -65.7606) (xy 439.4327 -64.2366) (xy 441.2107 -64.2366)
				)
			)
		)
	)
	(footprint ""
		(layer "B.Cu")
		(at 389.33755 -111.05515 180)
		(property "Reference" "C2N4"
			(at 0 0 0)
			(layer "B.SilkS")
			(hide yes)
			(effects
				(font
					(size 1.27 1.27)
				)
				(justify mirror)
			)
		)
		(property "Value" ""
			(at 0 0 0)
			(layer "B.Fab")
			(effects
				(font
					(size 1.27 1.27)
				)
				(justify mirror)
			)
		)
		(duplicate_pad_numbers_are_jumpers no)
		(fp_rect
			(start 0.2794 0.9144)
			(end -0.2794 -0.1143)
			(stroke
				(width 0)
				(type default)
			)
			(fill no)
			(layer "B.CrtYd")
		)
		(fp_line
			(start 0.2794 0.9144)
			(end 0.2794 -0.1143)
			(stroke
				(width 0.1)
				(type default)
			)
			(layer "B.Fab")
		)
		(fp_line
			(start 0.2794 -0.1143)
			(end -0.2794 -0.1143)
			(stroke
				(width 0.1)
				(type default)
			)
			(layer "B.Fab")
		)
		(fp_line
			(start -0.2794 0.9144)
			(end 0.2794 0.9144)
			(stroke
				(width 0.1)
				(type default)
			)
			(layer "B.Fab")
		)
		(fp_line
			(start -0.2794 -0.1143)
			(end -0.2794 0.9144)
			(stroke
				(width 0.1)
				(type default)
			)
			(layer "B.Fab")
		)
		(pad "1" smd custom
			(at 0 0 90)
			(size 0.10414 0.10414)
			(layers "B.Cu" "B.Mask" "B.Paste")
			(net "PVNN_PCH_STBY")
			(options
				(clearance outline)
				(anchor circle)
			)
			(primitives
				(gr_poly
					(pts
						(xy -0.20828 -0.08636) (xy -0.20828 0.08636) (xy -0.08636 0.20828) (xy 0.086614 0.20828) (xy 0.20828 0.086614)
						(xy 0.20828 -0.08636) (xy 0.08636 -0.20828) (xy -0.08636 -0.20828)
					)
					(width 0)
					(fill yes)
				)
			)
		)
		(pad "2" smd custom
			(at 0 0.8001 90)
			(size 0.10414 0.10414)
			(layers "B.Cu" "B.Mask" "B.Paste")
			(net "GND")
			(options
				(clearance outline)
				(anchor circle)
			)
			(primitives
				(gr_poly
					(pts
						(xy -0.20828 -0.08636) (xy -0.20828 0.08636) (xy -0.08636 0.20828) (xy 0.086614 0.20828) (xy 0.20828 0.086614)
						(xy 0.20828 -0.08636) (xy 0.08636 -0.20828) (xy -0.08636 -0.20828)
					)
					(width 0)
					(fill yes)
				)
			)
		)
		(zone
			(layer "B.Cu")
			(hatch none 0.5)
			(connect_pads
				(clearance 0)
			)
			(min_thickness 0.25)
			(keepout
				(tracks allowed)
				(vias not_allowed)
				(pads allowed)
				(copperpour not_allowed)
				(footprints allowed)
			)
			(placement
				(enabled no)
				(sheetname "")
			)
			(fill
				(thermal_gap 0.5)
				(thermal_bridge_width 0.5)
				(island_removal_mode 0)
			)
			(polygon
				(pts
					(xy 389.24992 -111.2647) (xy 389.24992 -111.6457) (xy 389.42518 -111.6457) (xy 389.425434 -111.2647)
				)
			)
		)
		(zone
			(layer "B.Cu")
			(hatch none 0.5)
			(connect_pads
				(clearance 0)
			)
			(min_thickness 0.25)
			(keepout
				(tracks not_allowed)
				(vias allowed)
				(pads allowed)
				(copperpour not_allowed)
				(footprints allowed)
			)
			(placement
				(enabled no)
				(sheetname "")
			)
			(fill
				(thermal_gap 0.5)
				(thermal_bridge_width 0.5)
				(island_removal_mode 0)
			)
			(polygon
				(pts
					(xy 389.24992 -111.2647) (xy 389.24992 -111.6457) (xy 389.42518 -111.6457) (xy 389.425434 -111.2647)
				)
			)
		)
	)
	(footprint ""
		(layer "B.Cu")
		(at 409.829 -48.768)
		(property "Reference" "R1T4"
			(at 0 0 0)
			(layer "B.SilkS")
			(hide yes)
			(effects
				(font
					(size 1.27 1.27)
				)
				(justify mirror)
			)
		)
		(property "Value" ""
			(at 0 0 0)
			(layer "B.Fab")
			(effects
				(font
					(size 1.27 1.27)
				)
				(justify mirror)
			)
		)
		(duplicate_pad_numbers_are_jumpers no)
		(fp_poly
			(pts
				(xy 0.2794 -0.1016) (xy -0.2794 -0.1016) (xy -0.2794 0.9906) (xy 0.2794 0.9906)
			)
			(stroke
				(width 0)
				(type default)
			)
			(fill no)
			(layer "B.CrtYd")
		)
		(fp_line
			(start -0.2794 -0.1016)
			(end 0.2794 -0.1016)
			(stroke
				(width 0.1)
				(type default)
			)
			(layer "B.Fab")
		)
		(fp_line
			(start -0.2794 0.9906)
			(end -0.2794 -0.1016)
			(stroke
				(width 0.1)
				(type default)
			)
			(layer "B.Fab")
		)
		(fp_line
			(start 0.2794 -0.1016)
			(end 0.2794 0.9906)
			(stroke
				(width 0.1)
				(type default)
			)
			(layer "B.Fab")
		)
		(fp_line
			(start 0.2794 0.9906)
			(end -0.2794 0.9906)
			(stroke
				(width 0.1)
				(type default)
			)
			(layer "B.Fab")
		)
		(pad "1" smd rect
			(at 0 0 180)
			(size 0.508 0.508)
			(layers "B.Cu" "B.Mask" "B.Paste")
			(net "P3V3_STBY")
		)
		(pad "2" smd rect
			(at 0 0.889 180)
			(size 0.508 0.508)
			(layers "B.Cu" "B.Mask" "B.Paste")
			(net "FM_BOARD_REV_ID0")
		)
	)
	(footprint ""
		(layer "B.Cu")
		(at 32.3088 -70.7898 90)
		(property "Reference" "R9P22"
			(at 0 0 90)
			(layer "B.SilkS")
			(hide yes)
			(effects
				(font
					(size 1.27 1.27)
				)
				(justify mirror)
			)
		)
		(property "Value" ""
			(at 0 0 90)
			(layer "B.Fab")
			(effects
				(font
					(size 1.27 1.27)
				)
				(justify mirror)
			)
		)
		(duplicate_pad_numbers_are_jumpers no)
		(fp_poly
			(pts
				(xy 0.2794 -0.1016) (xy -0.2794 -0.1016) (xy -0.2794 0.9906) (xy 0.2794 0.9906)
			)
			(stroke
				(width 0)
				(type default)
			)
			(fill no)
			(layer "B.CrtYd")
		)
		(fp_line
			(start 0.2794 -0.1016)
			(end 0.2794 0.9906)
			(stroke
				(width 0.1)
				(type default)
			)
			(layer "B.Fab")
		)
		(fp_line
			(start -0.2794 -0.1016)
			(end 0.2794 -0.1016)
			(stroke
				(width 0.1)
				(type default)
			)
			(layer "B.Fab")
		)
		(fp_line
			(start 0.2794 0.9906)
			(end -0.2794 0.9906)
			(stroke
				(width 0.1)
				(type default)
			)
			(layer "B.Fab")
		)
		(fp_line
			(start -0.2794 0.9906)
			(end -0.2794 -0.1016)
			(stroke
				(width 0.1)
				(type default)
			)
			(layer "B.Fab")
		)
		(pad "1" smd rect
			(at 0 0 270)
			(size 0.508 0.508)
			(layers "B.Cu" "B.Mask" "B.Paste")
			(net "VR_PVCCIN_CPU1_PH3_VCIN")
		)
		(pad "2" smd rect
			(at 0 0.889 270)
			(size 0.508 0.508)
			(layers "B.Cu" "B.Mask" "B.Paste")
			(net "P5V_STBY")
		)
		(zone
			(layer "B.Cu")
			(hatch none 0.5)
			(connect_pads
				(clearance 0)
			)
			(min_thickness 0.25)
			(keepout
				(tracks allowed)
				(vias not_allowed)
				(pads allowed)
				(copperpour not_allowed)
				(footprints allowed)
			)
			(placement
				(enabled no)
				(sheetname "")
			)
			(fill
				(thermal_gap 0.5)
				(thermal_bridge_width 0.5)
				(island_removal_mode 0)
			)
			(polygon
				(pts
					(xy 32.5628 -71.0438) (xy 32.5628 -70.5358) (xy 32.9438 -70.5358) (xy 32.9438 -71.0438)
				)
			)
		)
		(zone
			(layer "B.Cu")
			(hatch none 0.5)
			(connect_pads
				(clearance 0)
			)
			(min_thickness 0.25)
			(keepout
				(tracks not_allowed)
				(vias allowed)
				(pads allowed)
				(copperpour not_allowed)
				(footprints allowed)
			)
			(placement
				(enabled no)
				(sheetname "")
			)
			(fill
				(thermal_gap 0.5)
				(thermal_bridge_width 0.5)
				(island_removal_mode 0)
			)
			(polygon
				(pts
					(xy 32.9438 -71.0438) (xy 32.9438 -70.5358) (xy 32.5628 -70.5358) (xy 32.5628 -71.0438)
				)
			)
		)
	)
	(footprint ""
		(layer "B.Cu")
		(at 362.715556 -122.510042 -90)
		(property "Reference" "C3M26"
			(at 0 0 90)
			(layer "B.SilkS")
			(hide yes)
			(effects
				(font
					(size 1.27 1.27)
				)
				(justify mirror)
			)
		)
		(property "Value" ""
			(at 0 0 90)
			(layer "B.Fab")
			(effects
				(font
					(size 1.27 1.27)
				)
				(justify mirror)
			)
		)
		(duplicate_pad_numbers_are_jumpers no)
		(fp_poly
			(pts
				(xy -0.3048 -0.1016) (xy -0.3048 0.9906) (xy 0.3048 0.9906) (xy 0.3048 -0.1016)
			)
			(stroke
				(width 0)
				(type default)
			)
			(fill no)
			(layer "B.CrtYd")
		)
		(fp_line
			(start -0.3048 0.9906)
			(end -0.3048 -0.1016)
			(stroke
				(width 0.1)
				(type default)
			)
			(layer "B.Fab")
		)
		(fp_line
			(start 0.3048 0.9906)
			(end -0.3048 0.9906)
			(stroke
				(width 0.1)
				(type default)
			)
			(layer "B.Fab")
		)
		(fp_line
			(start -0.3048 -0.1016)
			(end 0.3048 -0.1016)
			(stroke
				(width 0.1)
				(type default)
			)
			(layer "B.Fab")
		)
		(fp_line
			(start 0.3048 -0.1016)
			(end 0.3048 0.9906)
			(stroke
				(width 0.1)
				(type default)
			)
			(layer "B.Fab")
		)
		(pad "1" smd rect
			(at 0 0 90)
			(size 0.508 0.508)
			(layers "B.Cu" "B.Mask" "B.Paste")
			(net "P3E_CPU0_PE1_PCH_R_RXN<11>")
		)
		(pad "2" smd rect
			(at 0 0.889 90)
			(size 0.508 0.508)
			(layers "B.Cu" "B.Mask" "B.Paste")
			(net "P3E_CPU0_PE1_PCH_RXN<11>")
		)
		(zone
			(layer "B.Cu")
			(hatch none 0.5)
			(connect_pads
				(clearance 0)
			)
			(min_thickness 0.25)
			(keepout
				(tracks not_allowed)
				(vias allowed)
				(pads allowed)
				(copperpour not_allowed)
				(footprints allowed)
			)
			(placement
				(enabled no)
				(sheetname "")
			)
			(fill
				(thermal_gap 0.5)
				(thermal_bridge_width 0.5)
				(island_removal_mode 0)
			)
			(polygon
				(pts
					(xy 362.080556 -122.256042) (xy 362.080556 -122.764042) (xy 362.461556 -122.764042) (xy 362.461556 -122.256042)
				)
			)
		)
		(zone
			(layer "B.Cu")
			(hatch none 0.5)
			(connect_pads
				(clearance 0)
			)
			(min_thickness 0.25)
			(keepout
				(tracks allowed)
				(vias not_allowed)
				(pads allowed)
				(copperpour not_allowed)
				(footprints allowed)
			)
			(placement
				(enabled no)
				(sheetname "")
			)
			(fill
				(thermal_gap 0.5)
				(thermal_bridge_width 0.5)
				(island_removal_mode 0)
			)
			(polygon
				(pts
					(xy 362.461556 -122.256042) (xy 362.461556 -122.764042) (xy 362.080556 -122.764042) (xy 362.080556 -122.256042)
				)
			)
		)
	)
	(footprint ""
		(layer "B.Cu")
		(at 395.351 -85.9155)
		(property "Reference" "R2U8"
			(at 0 0 0)
			(layer "B.SilkS")
			(hide yes)
			(effects
				(font
					(size 1.27 1.27)
				)
				(justify mirror)
			)
		)
		(property "Value" ""
			(at 0 0 0)
			(layer "B.Fab")
			(effects
				(font
					(size 1.27 1.27)
				)
				(justify mirror)
			)
		)
		(duplicate_pad_numbers_are_jumpers no)
		(fp_poly
			(pts
				(xy 0.2794 -0.1016) (xy -0.2794 -0.1016) (xy -0.2794 0.9906) (xy 0.2794 0.9906)
			)
			(stroke
				(width 0)
				(type default)
			)
			(fill no)
			(layer "B.CrtYd")
		)
		(fp_line
			(start -0.2794 -0.1016)
			(end 0.2794 -0.1016)
			(stroke
				(width 0.1)
				(type default)
			)
			(layer "B.Fab")
		)
		(fp_line
			(start -0.2794 0.9906)
			(end -0.2794 -0.1016)
			(stroke
				(width 0.1)
				(type default)
			)
			(layer "B.Fab")
		)
		(fp_line
			(start 0.2794 -0.1016)
			(end 0.2794 0.9906)
			(stroke
				(width 0.1)
				(type default)
			)
			(layer "B.Fab")
		)
		(fp_line
			(start 0.2794 0.9906)
			(end -0.2794 0.9906)
			(stroke
				(width 0.1)
				(type default)
			)
			(layer "B.Fab")
		)
		(pad "1" smd rect
			(at 0 0 180)
			(size 0.508 0.508)
			(layers "B.Cu" "B.Mask" "B.Paste")
			(net "SMB_LAN_STBY_LVC3_SCL")
		)
		(pad "2" smd rect
			(at 0 0.889 180)
			(size 0.508 0.508)
			(layers "B.Cu" "B.Mask" "B.Paste")
			(net "SMB_OCP_FRU_STBY_LVC3_SCL")
		)
		(zone
			(layer "B.Cu")
			(hatch none 0.5)
			(connect_pads
				(clearance 0)
			)
			(min_thickness 0.25)
			(keepout
				(tracks allowed)
				(vias not_allowed)
				(pads allowed)
				(copperpour not_allowed)
				(footprints allowed)
			)
			(placement
				(enabled no)
				(sheetname "")
			)
			(fill
				(thermal_gap 0.5)
				(thermal_bridge_width 0.5)
				(island_removal_mode 0)
			)
			(polygon
				(pts
					(xy 395.605 -85.6615) (xy 395.097 -85.6615) (xy 395.097 -85.2805) (xy 395.605 -85.2805)
				)
			)
		)
		(zone
			(layer "B.Cu")
			(hatch none 0.5)
			(connect_pads
				(clearance 0)
			)
			(min_thickness 0.25)
			(keepout
				(tracks not_allowed)
				(vias allowed)
				(pads allowed)
				(copperpour not_allowed)
				(footprints allowed)
			)
			(placement
				(enabled no)
				(sheetname "")
			)
			(fill
				(thermal_gap 0.5)
				(thermal_bridge_width 0.5)
				(island_removal_mode 0)
			)
			(polygon
				(pts
					(xy 395.605 -85.2805) (xy 395.097 -85.2805) (xy 395.097 -85.6615) (xy 395.605 -85.6615)
				)
			)
		)
	)
	(footprint ""
		(layer "B.Cu")
		(at 25.654 -77.978)
		(property "Reference" "C9P11"
			(at 0 0 0)
			(layer "B.SilkS")
			(hide yes)
			(effects
				(font
					(size 1.27 1.27)
				)
				(justify mirror)
			)
		)
		(property "Value" ""
			(at 0 0 0)
			(layer "B.Fab")
			(effects
				(font
					(size 1.27 1.27)
				)
				(justify mirror)
			)
		)
		(duplicate_pad_numbers_are_jumpers no)
		(fp_poly
			(pts
				(xy -0.3048 -0.1016) (xy -0.3048 0.9906) (xy 0.3048 0.9906) (xy 0.3048 -0.1016)
			)
			(stroke
				(width 0)
				(type default)
			)
			(fill no)
			(layer "B.CrtYd")
		)
		(fp_line
			(start -0.3048 -0.1016)
			(end 0.3048 -0.1016)
			(stroke
				(width 0.1)
				(type default)
			)
			(layer "B.Fab")
		)
		(fp_line
			(start -0.3048 0.9906)
			(end -0.3048 -0.1016)
			(stroke
				(width 0.1)
				(type default)
			)
			(layer "B.Fab")
		)
		(fp_line
			(start 0.3048 -0.1016)
			(end 0.3048 0.9906)
			(stroke
				(width 0.1)
				(type default)
			)
			(layer "B.Fab")
		)
		(fp_line
			(start 0.3048 0.9906)
			(end -0.3048 0.9906)
			(stroke
				(width 0.1)
				(type default)
			)
			(layer "B.Fab")
		)
		(pad "1" smd rect
			(at 0 0 180)
			(size 0.508 0.508)
			(layers "B.Cu" "B.Mask" "B.Paste")
			(net "P3V3_STBY")
		)
		(pad "2" smd rect
			(at 0 0.889 180)
			(size 0.508 0.508)
			(layers "B.Cu" "B.Mask" "B.Paste")
			(net "GND")
		)
		(zone
			(layer "B.Cu")
			(hatch none 0.5)
			(connect_pads
				(clearance 0)
			)
			(min_thickness 0.25)
			(keepout
				(tracks allowed)
				(vias not_allowed)
				(pads allowed)
				(copperpour not_allowed)
				(footprints allowed)
			)
			(placement
				(enabled no)
				(sheetname "")
			)
			(fill
				(thermal_gap 0.5)
				(thermal_bridge_width 0.5)
				(island_removal_mode 0)
			)
			(polygon
				(pts
					(xy 25.908 -77.724) (xy 25.4 -77.724) (xy 25.4 -77.343) (xy 25.908 -77.343)
				)
			)
		)
		(zone
			(layer "B.Cu")
			(hatch none 0.5)
			(connect_pads
				(clearance 0)
			)
			(min_thickness 0.25)
			(keepout
				(tracks not_allowed)
				(vias allowed)
				(pads allowed)
				(copperpour not_allowed)
				(footprints allowed)
			)
			(placement
				(enabled no)
				(sheetname "")
			)
			(fill
				(thermal_gap 0.5)
				(thermal_bridge_width 0.5)
				(island_removal_mode 0)
			)
			(polygon
				(pts
					(xy 25.908 -77.343) (xy 25.4 -77.343) (xy 25.4 -77.724) (xy 25.908 -77.724)
				)
			)
		)
	)
)
